(kicad_pcb
	(version 20260206)
	(generator "pcbnew")
	(generator_version "10.0")
	(general
		(thickness 1.6)
		(legacy_teardrops no)
	)
	(paper "A4")
	(title_block
		(title "peb — Lightning_PEB_BRD.brd")
		(comment 1 "Lightning (Wiwynn / Facebook NVMe JBOF) / footprints 1571-1578 of 2563")
	)
	(layers
		(0 "F.Cu" signal "TOP")
		(4 "In1.Cu" signal "L2GND")
		(6 "In2.Cu" signal "L3")
		(8 "In3.Cu" signal "L4VCC")
		(10 "In4.Cu" signal "L5VCC")
		(12 "In5.Cu" signal "L6")
		(14 "In6.Cu" signal "L7GND")
		(2 "B.Cu" signal "BOTTOM")
		(9 "F.Adhes" user "F.Adhesive")
		(11 "B.Adhes" user "B.Adhesive")
		(13 "F.Paste" user "Package Geometry/Pastemask Top")
		(15 "B.Paste" user "Package Geometry/Pastemask Bottom")
		(5 "F.SilkS" user "Ref Des/Silkscreen Top")
		(7 "B.SilkS" user "Ref Des/Silkscreen Bottom")
		(1 "F.Mask" user "Board Geometry/Soldermask Top")
		(3 "B.Mask" user "Board Geometry/Soldermask Bottom")
		(17 "Dwgs.User" user "User.Drawings")
		(19 "Cmts.User" user "User.Comments")
		(21 "Eco1.User" user "User.Eco1")
		(23 "Eco2.User" user "User.Eco2")
		(25 "Edge.Cuts" user "Board Geometry/Outline")
		(27 "Margin" user)
		(31 "F.CrtYd" user "Package Geometry/Place Bound Top")
		(29 "B.CrtYd" user "Package Geometry/Place Bound Bottom")
		(35 "F.Fab" user "Ref Des/Assembly Top")
		(33 "B.Fab" user "Ref Des/Assembly Bottom")
	)
	(footprint ""
		(layer "F.Cu")
		(at 119.351806 -82.34934 -90)
		(property "Reference" "C1698"
			(at 0 0 270)
			(layer "F.SilkS")
			(hide yes)
			(effects
				(font
					(size 1.27 1.27)
				)
			)
		)
		(property "Value" "SC22UF16V6KX-GP"
			(at 0 -6.8072 270)
			(unlocked yes)
			(layer "F.Fab")
			(hide yes)
			(effects
				(font
					(size 1.016 1.016)
					(thickness 0.1524)
				)
			)
		)
		(property "Device Type" "C1206H75"
			(at 0 -8.7122 270)
			(unlocked yes)
			(layer "F.Fab")
			(hide yes)
			(effects
				(font
					(size 1.016 1.016)
					(thickness 0.1524)
				)
			)
		)
		(duplicate_pad_numbers_are_jumpers no)
		(fp_line
			(start -1.016 2.2352)
			(end -1.016 0.8128)
			(stroke
				(width 0.1524)
				(type default)
			)
			(layer "F.SilkS")
		)
		(fp_line
			(start 1.016 2.2352)
			(end -1.016 2.2352)
			(stroke
				(width 0.1524)
				(type default)
			)
			(layer "F.SilkS")
		)
		(fp_line
			(start 1.016 0.8382)
			(end 1.016 2.2352)
			(stroke
				(width 0.1524)
				(type default)
			)
			(layer "F.SilkS")
		)
		(fp_line
			(start -1.016 -2.2352)
			(end -1.016 -0.8382)
			(stroke
				(width 0.1524)
				(type default)
			)
			(layer "F.SilkS")
		)
		(fp_line
			(start 1.016 -2.2352)
			(end 1.016 -0.8382)
			(stroke
				(width 0.1524)
				(type default)
			)
			(layer "F.SilkS")
		)
		(fp_line
			(start 1.016 -2.2352)
			(end -1.016 -2.2352)
			(stroke
				(width 0.1524)
				(type default)
			)
			(layer "F.SilkS")
		)
		(fp_rect
			(start -1.0922 2.3114)
			(end 1.0922 -2.3114)
			(stroke
				(width 0)
				(type default)
			)
			(fill no)
			(layer "F.CrtYd")
		)
		(fp_poly
			(pts
				(xy -1.0922 -2.3114) (xy 1.0922 -2.3114) (xy 1.0922 2.3114) (xy -1.0922 2.3114)
			)
			(stroke
				(width 0)
				(type default)
			)
			(fill no)
			(layer "F.Fab")
		)
		(pad "1" smd rect
			(at 0 -1.397 270)
			(size 1.651 1.27)
			(layers "F.Cu" "F.Mask" "F.Paste")
			(net "P3V3_RTC")
		)
		(pad "2" smd rect
			(at 0 1.397 270)
			(size 1.651 1.27)
			(layers "F.Cu" "F.Mask" "F.Paste")
			(net "GND")
		)
	)
	(footprint ""
		(layer "F.Cu")
		(at 20.6502 -189.2046 -90)
		(property "Reference" "R2107"
			(at 0 0 270)
			(layer "F.SilkS")
			(hide yes)
			(effects
				(font
					(size 1.27 1.27)
				)
			)
		)
		(property "Value" "49K9R2F-L-GP"
			(at 0.064008 -3.993896 270)
			(unlocked yes)
			(layer "F.Fab")
			(hide yes)
			(effects
				(font
					(size 1.016 1.016)
					(thickness 0.1524)
				)
			)
		)
		(property "Device Type" "R402H16"
			(at 0.064008 -5.517896 270)
			(unlocked yes)
			(layer "F.Fab")
			(hide yes)
			(effects
				(font
					(size 1.016 1.016)
					(thickness 0.1524)
				)
			)
		)
		(duplicate_pad_numbers_are_jumpers no)
		(fp_line
			(start -0.508 -0.9398)
			(end -0.508 0.9398)
			(stroke
				(width 0.1524)
				(type default)
			)
			(layer "F.SilkS")
		)
		(fp_line
			(start 0.508 -0.9398)
			(end -0.508 -0.9398)
			(stroke
				(width 0.1524)
				(type default)
			)
			(layer "F.SilkS")
		)
		(fp_rect
			(start -0.508 0.9398)
			(end 0.508 -0.9398)
			(stroke
				(width 0)
				(type default)
			)
			(fill no)
			(layer "F.CrtYd")
		)
		(fp_rect
			(start -0.508 0.9398)
			(end 0.508 -0.9398)
			(stroke
				(width 0)
				(type default)
			)
			(fill no)
			(layer "F.Fab")
		)
		(pad "1" smd custom
			(at 0 -0.4445 270)
			(size 0.1397 0.1397)
			(layers "F.Cu" "F.Mask" "F.Paste")
			(net "P12V_PCIE")
			(options
				(clearance outline)
				(anchor circle)
			)
			(primitives
				(gr_poly
					(pts
						(arc
							(start -0.1778 -0.2794)
							(mid -0.249642 -0.249642)
							(end -0.2794 -0.1778)
						)
						(arc
							(start -0.2794 0.1778)
							(mid -0.249642 0.249642)
							(end -0.1778 0.2794)
						)
						(arc
							(start 0.1778 0.2794)
							(mid 0.249642 0.249642)
							(end 0.2794 0.1778)
						)
						(arc
							(start 0.2794 -0.1778)
							(mid 0.249642 -0.249642)
							(end 0.1778 -0.2794)
						)
					)
					(width 0)
					(fill yes)
				)
			)
		)
		(pad "2" smd custom
			(at 0 0.4445 270)
			(size 0.1397 0.1397)
			(layers "F.Cu" "F.Mask" "F.Paste")
			(net "MB0_CM_UV_R")
			(options
				(clearance outline)
				(anchor circle)
			)
			(primitives
				(gr_poly
					(pts
						(arc
							(start -0.1778 -0.2794)
							(mid -0.249642 -0.249642)
							(end -0.2794 -0.1778)
						)
						(arc
							(start -0.2794 0.1778)
							(mid -0.249642 0.249642)
							(end -0.1778 0.2794)
						)
						(arc
							(start 0.1778 0.2794)
							(mid 0.249642 0.249642)
							(end 0.2794 0.1778)
						)
						(arc
							(start 0.2794 -0.1778)
							(mid 0.249642 -0.249642)
							(end 0.1778 -0.2794)
						)
					)
					(width 0)
					(fill yes)
				)
			)
		)
	)
	(footprint ""
		(layer "F.Cu")
		(at 72.771 -195.707 180)
		(property "Reference" "R9040"
			(at 0 0 180)
			(layer "F.SilkS")
			(hide yes)
			(effects
				(font
					(size 1.27 1.27)
				)
			)
		)
		(property "Value" "4K7R2F-GP"
			(at 0.064008 -3.993896 180)
			(unlocked yes)
			(layer "F.Fab")
			(hide yes)
			(effects
				(font
					(size 1.016 1.016)
					(thickness 0.1524)
				)
			)
		)
		(property "Device Type" "R402H16"
			(at 0.064008 -5.517896 180)
			(unlocked yes)
			(layer "F.Fab")
			(hide yes)
			(effects
				(font
					(size 1.016 1.016)
					(thickness 0.1524)
				)
			)
		)
		(duplicate_pad_numbers_are_jumpers no)
		(fp_line
			(start 0.508 -0.9398)
			(end -0.508 -0.9398)
			(stroke
				(width 0.1524)
				(type default)
			)
			(layer "F.SilkS")
		)
		(fp_line
			(start -0.508 -0.9398)
			(end -0.508 0.9398)
			(stroke
				(width 0.1524)
				(type default)
			)
			(layer "F.SilkS")
		)
		(fp_rect
			(start -0.508 0.9398)
			(end 0.508 -0.9398)
			(stroke
				(width 0)
				(type default)
			)
			(fill no)
			(layer "F.CrtYd")
		)
		(fp_rect
			(start -0.508 0.9398)
			(end 0.508 -0.9398)
			(stroke
				(width 0)
				(type default)
			)
			(fill no)
			(layer "F.Fab")
		)
		(pad "1" smd custom
			(at 0 -0.4445 180)
			(size 0.1397 0.1397)
			(layers "F.Cu" "F.Mask" "F.Paste")
			(net "SSD_PERST#11")
			(options
				(clearance outline)
				(anchor circle)
			)
			(primitives
				(gr_poly
					(pts
						(arc
							(start -0.1778 -0.2794)
							(mid -0.249642 -0.249642)
							(end -0.2794 -0.1778)
						)
						(arc
							(start -0.2794 0.1778)
							(mid -0.249642 0.249642)
							(end -0.1778 0.2794)
						)
						(arc
							(start 0.1778 0.2794)
							(mid 0.249642 0.249642)
							(end 0.2794 0.1778)
						)
						(arc
							(start 0.2794 -0.1778)
							(mid 0.249642 -0.249642)
							(end 0.1778 -0.2794)
						)
					)
					(width 0)
					(fill yes)
				)
			)
		)
		(pad "2" smd custom
			(at 0 0.4445 180)
			(size 0.1397 0.1397)
			(layers "F.Cu" "F.Mask" "F.Paste")
			(net "GND")
			(options
				(clearance outline)
				(anchor circle)
			)
			(primitives
				(gr_poly
					(pts
						(arc
							(start -0.1778 -0.2794)
							(mid -0.249642 -0.249642)
							(end -0.2794 -0.1778)
						)
						(arc
							(start -0.2794 0.1778)
							(mid -0.249642 0.249642)
							(end -0.1778 0.2794)
						)
						(arc
							(start 0.1778 0.2794)
							(mid 0.249642 0.249642)
							(end 0.2794 0.1778)
						)
						(arc
							(start 0.2794 -0.1778)
							(mid 0.249642 -0.249642)
							(end 0.1778 -0.2794)
						)
					)
					(width 0)
					(fill yes)
				)
			)
		)
	)
	(footprint ""
		(layer "F.Cu")
		(at 88.9 -44.0944)
		(property "Reference" "PG6"
			(at 0 0 0)
			(layer "F.SilkS")
			(hide yes)
			(effects
				(font
					(size 1.27 1.27)
				)
			)
		)
		(property "Value" "GAP-CLOSE-PWR-3-GP"
			(at 0.0254 -6.5786 0)
			(unlocked yes)
			(layer "F.Fab")
			(hide yes)
			(effects
				(font
					(size 1.016 1.016)
					(thickness 0.1524)
				)
			)
		)
		(property "Device Type" "GAP-CLOSE-PWR-3"
			(at 0.0254 -8.255 0)
			(unlocked yes)
			(layer "F.Fab")
			(hide yes)
			(effects
				(font
					(size 1.016 1.016)
					(thickness 0.1524)
				)
			)
		)
		(duplicate_pad_numbers_are_jumpers no)
		(fp_rect
			(start -0.7112 0.4572)
			(end 0.7112 -0.4572)
			(stroke
				(width 0)
				(type default)
			)
			(fill no)
			(layer "F.CrtYd")
		)
		(fp_poly
			(pts
				(xy -0.7112 -0.4572) (xy 0.7112 -0.4572) (xy 0.7112 0.4572) (xy -0.7112 0.4572)
			)
			(stroke
				(width 0)
				(type default)
			)
			(fill no)
			(layer "F.Fab")
		)
		(pad "1" smd rect
			(at -0.3048 0)
			(size 0.6604 0.762)
			(layers "F.Cu" "F.Mask" "F.Paste")
			(net "P3V3_PWR")
		)
		(pad "2" smd rect
			(at 0.3048 0)
			(size 0.6604 0.762)
			(layers "F.Cu" "F.Mask" "F.Paste")
			(net "P3V3_STBY")
		)
	)
	(footprint ""
		(layer "F.Cu")
		(at 20.955 -140.843 -90)
		(property "Reference" "R607"
			(at 0 0 270)
			(layer "F.SilkS")
			(hide yes)
			(effects
				(font
					(size 1.27 1.27)
				)
			)
		)
		(property "Value" "0R2J-2-GP"
			(at 0.064008 -3.993896 270)
			(unlocked yes)
			(layer "F.Fab")
			(hide yes)
			(effects
				(font
					(size 1.016 1.016)
					(thickness 0.1524)
				)
			)
		)
		(property "Device Type" "R402H16"
			(at 0.064008 -5.517896 270)
			(unlocked yes)
			(layer "F.Fab")
			(hide yes)
			(effects
				(font
					(size 1.016 1.016)
					(thickness 0.1524)
				)
			)
		)
		(duplicate_pad_numbers_are_jumpers no)
		(fp_line
			(start -0.508 -0.9398)
			(end -0.508 0.9398)
			(stroke
				(width 0.1524)
				(type default)
			)
			(layer "F.SilkS")
		)
		(fp_line
			(start 0.508 -0.9398)
			(end -0.508 -0.9398)
			(stroke
				(width 0.1524)
				(type default)
			)
			(layer "F.SilkS")
		)
		(fp_rect
			(start -0.508 0.9398)
			(end 0.508 -0.9398)
			(stroke
				(width 0)
				(type default)
			)
			(fill no)
			(layer "F.CrtYd")
		)
		(fp_rect
			(start -0.508 0.9398)
			(end 0.508 -0.9398)
			(stroke
				(width 0)
				(type default)
			)
			(fill no)
			(layer "F.Fab")
		)
		(pad "1" smd custom
			(at 0 -0.4445 270)
			(size 0.1397 0.1397)
			(layers "F.Cu" "F.Mask" "F.Paste")
			(net "DP_RST_N_R")
			(options
				(clearance outline)
				(anchor circle)
			)
			(primitives
				(gr_poly
					(pts
						(arc
							(start -0.1778 -0.2794)
							(mid -0.249642 -0.249642)
							(end -0.2794 -0.1778)
						)
						(arc
							(start -0.2794 0.1778)
							(mid -0.249642 0.249642)
							(end -0.1778 0.2794)
						)
						(arc
							(start 0.1778 0.2794)
							(mid 0.249642 0.249642)
							(end 0.2794 0.1778)
						)
						(arc
							(start 0.2794 -0.1778)
							(mid 0.249642 -0.249642)
							(end 0.1778 -0.2794)
						)
					)
					(width 0)
					(fill yes)
				)
			)
		)
		(pad "2" smd custom
			(at 0 0.4445 270)
			(size 0.1397 0.1397)
			(layers "F.Cu" "F.Mask" "F.Paste")
			(net "DP_RST_N")
			(options
				(clearance outline)
				(anchor circle)
			)
			(primitives
				(gr_poly
					(pts
						(arc
							(start -0.1778 -0.2794)
							(mid -0.249642 -0.249642)
							(end -0.2794 -0.1778)
						)
						(arc
							(start -0.2794 0.1778)
							(mid -0.249642 0.249642)
							(end -0.1778 0.2794)
						)
						(arc
							(start 0.1778 0.2794)
							(mid 0.249642 0.249642)
							(end 0.2794 0.1778)
						)
						(arc
							(start 0.2794 -0.1778)
							(mid 0.249642 -0.249642)
							(end 0.1778 -0.2794)
						)
					)
					(width 0)
					(fill yes)
				)
			)
		)
	)
	(footprint ""
		(layer "F.Cu")
		(at 196.792088 -212.420454 180)
		(property "Reference" "C119"
			(at 0 0 180)
			(layer "F.SilkS")
			(hide yes)
			(effects
				(font
					(size 1.27 1.27)
				)
			)
		)
		(property "Value" "SCD22U10V2KX-1GP"
			(at 1.1811 -2.7051 180)
			(unlocked yes)
			(layer "F.Fab")
			(hide yes)
			(effects
				(font
					(size 1.016 1.016)
					(thickness 0.1524)
				)
			)
		)
		(property "Device Type" "C402H22"
			(at 1.1811 -4.2291 180)
			(unlocked yes)
			(layer "F.Fab")
			(hide yes)
			(effects
				(font
					(size 1.016 1.016)
					(thickness 0.1524)
				)
			)
		)
		(duplicate_pad_numbers_are_jumpers no)
		(fp_rect
			(start -0.4318 0.9525)
			(end 0.4318 -0.9525)
			(stroke
				(width 0)
				(type default)
			)
			(fill no)
			(layer "F.CrtYd")
		)
		(fp_rect
			(start -0.4318 0.9525)
			(end 0.4318 -0.9525)
			(stroke
				(width 0)
				(type default)
			)
			(fill no)
			(layer "F.Fab")
		)
		(pad "1" smd custom
			(at 0 -0.4445 180)
			(size 0.1524 0.1524)
			(layers "F.Cu" "F.Mask" "F.Paste")
			(net "PCIE_TX_CAP_P43")
			(options
				(clearance outline)
				(anchor circle)
			)
			(primitives
				(gr_poly
					(pts
						(arc
							(start 0.3048 -0.2032)
							(mid 0.275042 -0.275042)
							(end 0.2032 -0.3048)
						)
						(arc
							(start -0.2032 -0.3048)
							(mid -0.275042 -0.275042)
							(end -0.3048 -0.2032)
						)
						(arc
							(start -0.3048 0.2032)
							(mid -0.275042 0.275042)
							(end -0.2032 0.3048)
						)
						(arc
							(start 0.2032 0.3048)
							(mid 0.275042 0.275042)
							(end 0.3048 0.2032)
						)
					)
					(width 0)
					(fill yes)
				)
			)
		)
		(pad "2" smd custom
			(at 0 0.4445 180)
			(size 0.1524 0.1524)
			(layers "F.Cu" "F.Mask" "F.Paste")
			(net "PCIE_TX_P43")
			(options
				(clearance outline)
				(anchor circle)
			)
			(primitives
				(gr_poly
					(pts
						(arc
							(start 0.3048 -0.2032)
							(mid 0.275042 -0.275042)
							(end 0.2032 -0.3048)
						)
						(arc
							(start -0.2032 -0.3048)
							(mid -0.275042 -0.275042)
							(end -0.3048 -0.2032)
						)
						(arc
							(start -0.3048 0.2032)
							(mid -0.275042 0.275042)
							(end -0.2032 0.3048)
						)
						(arc
							(start 0.2032 0.3048)
							(mid 0.275042 0.275042)
							(end 0.3048 0.2032)
						)
					)
					(width 0)
					(fill yes)
				)
			)
		)
	)
	(footprint ""
		(layer "F.Cu")
		(at 22.352 -154.5844)
		(property "Reference" "R493"
			(at 0 0 0)
			(layer "F.SilkS")
			(hide yes)
			(effects
				(font
					(size 1.27 1.27)
				)
			)
		)
		(property "Value" "4K7R2F-GP"
			(at 0.064008 -3.993896 0)
			(unlocked yes)
			(layer "F.Fab")
			(hide yes)
			(effects
				(font
					(size 1.016 1.016)
					(thickness 0.1524)
				)
			)
		)
		(property "Device Type" "R402H16"
			(at 0.064008 -5.517896 0)
			(unlocked yes)
			(layer "F.Fab")
			(hide yes)
			(effects
				(font
					(size 1.016 1.016)
					(thickness 0.1524)
				)
			)
		)
		(duplicate_pad_numbers_are_jumpers no)
		(fp_line
			(start -0.508 -0.9398)
			(end -0.508 0.9398)
			(stroke
				(width 0.1524)
				(type default)
			)
			(layer "F.SilkS")
		)
		(fp_line
			(start 0.508 -0.9398)
			(end -0.508 -0.9398)
			(stroke
				(width 0.1524)
				(type default)
			)
			(layer "F.SilkS")
		)
		(fp_rect
			(start -0.508 0.9398)
			(end 0.508 -0.9398)
			(stroke
				(width 0)
				(type default)
			)
			(fill no)
			(layer "F.CrtYd")
		)
		(fp_rect
			(start -0.508 0.9398)
			(end 0.508 -0.9398)
			(stroke
				(width 0)
				(type default)
			)
			(fill no)
			(layer "F.Fab")
		)
		(pad "1" smd custom
			(at 0 -0.4445)
			(size 0.1397 0.1397)
			(layers "F.Cu" "F.Mask" "F.Paste")
			(net "P3V3_STBY")
			(options
				(clearance outline)
				(anchor circle)
			)
			(primitives
				(gr_poly
					(pts
						(arc
							(start -0.1778 -0.2794)
							(mid -0.249642 -0.249642)
							(end -0.2794 -0.1778)
						)
						(arc
							(start -0.2794 0.1778)
							(mid -0.249642 0.249642)
							(end -0.1778 0.2794)
						)
						(arc
							(start 0.1778 0.2794)
							(mid 0.249642 0.249642)
							(end 0.2794 0.1778)
						)
						(arc
							(start 0.2794 -0.1778)
							(mid 0.249642 -0.249642)
							(end 0.1778 -0.2794)
						)
					)
					(width 0)
					(fill yes)
				)
			)
		)
		(pad "2" smd custom
			(at 0 0.4445)
			(size 0.1397 0.1397)
			(layers "F.Cu" "F.Mask" "F.Paste")
			(net "FM_BMC_RESET_Q36_R")
			(options
				(clearance outline)
				(anchor circle)
			)
			(primitives
				(gr_poly
					(pts
						(arc
							(start -0.1778 -0.2794)
							(mid -0.249642 -0.249642)
							(end -0.2794 -0.1778)
						)
						(arc
							(start -0.2794 0.1778)
							(mid -0.249642 0.249642)
							(end -0.1778 0.2794)
						)
						(arc
							(start 0.1778 0.2794)
							(mid 0.249642 0.249642)
							(end 0.2794 0.1778)
						)
						(arc
							(start 0.2794 -0.1778)
							(mid 0.249642 -0.249642)
							(end 0.1778 -0.2794)
						)
					)
					(width 0)
					(fill yes)
				)
			)
		)
	)
	(footprint ""
		(layer "F.Cu")
		(at 219.831412 -203.055474)
		(property "Reference" "R557"
			(at 0 0 0)
			(layer "F.SilkS")
			(hide yes)
			(effects
				(font
					(size 1.27 1.27)
				)
			)
		)
		(property "Value" "10KR2F-2-GP"
			(at 0.064008 -3.993896 0)
			(unlocked yes)
			(layer "F.Fab")
			(hide yes)
			(effects
				(font
					(size 1.016 1.016)
					(thickness 0.1524)
				)
			)
		)
		(property "Device Type" "R402H16"
			(at 0.064008 -5.517896 0)
			(unlocked yes)
			(layer "F.Fab")
			(hide yes)
			(effects
				(font
					(size 1.016 1.016)
					(thickness 0.1524)
				)
			)
		)
		(duplicate_pad_numbers_are_jumpers no)
		(fp_line
			(start -0.508 -0.9398)
			(end -0.508 0.9398)
			(stroke
				(width 0.1524)
				(type default)
			)
			(layer "F.SilkS")
		)
		(fp_line
			(start 0.508 -0.9398)
			(end -0.508 -0.9398)
			(stroke
				(width 0.1524)
				(type default)
			)
			(layer "F.SilkS")
		)
		(fp_rect
			(start -0.508 0.9398)
			(end 0.508 -0.9398)
			(stroke
				(width 0)
				(type default)
			)
			(fill no)
			(layer "F.CrtYd")
		)
		(fp_rect
			(start -0.508 0.9398)
			(end 0.508 -0.9398)
			(stroke
				(width 0)
				(type default)
			)
			(fill no)
			(layer "F.Fab")
		)
		(pad "1" smd custom
			(at 0 -0.4445)
			(size 0.1397 0.1397)
			(layers "F.Cu" "F.Mask" "F.Paste")
			(net "GND")
			(options
				(clearance outline)
				(anchor circle)
			)
			(primitives
				(gr_poly
					(pts
						(arc
							(start -0.1778 -0.2794)
							(mid -0.249642 -0.249642)
							(end -0.2794 -0.1778)
						)
						(arc
							(start -0.2794 0.1778)
							(mid -0.249642 0.249642)
							(end -0.1778 0.2794)
						)
						(arc
							(start 0.1778 0.2794)
							(mid 0.249642 0.249642)
							(end 0.2794 0.1778)
						)
						(arc
							(start 0.2794 -0.1778)
							(mid 0.249642 -0.249642)
							(end 0.1778 -0.2794)
						)
					)
					(width 0)
					(fill yes)
				)
			)
		)
		(pad "2" smd custom
			(at 0 0.4445)
			(size 0.1397 0.1397)
			(layers "F.Cu" "F.Mask" "F.Paste")
			(net "IOEXP3_AD0")
			(options
				(clearance outline)
				(anchor circle)
			)
			(primitives
				(gr_poly
					(pts
						(arc
							(start -0.1778 -0.2794)
							(mid -0.249642 -0.249642)
							(end -0.2794 -0.1778)
						)
						(arc
							(start -0.2794 0.1778)
							(mid -0.249642 0.249642)
							(end -0.1778 0.2794)
						)
						(arc
							(start 0.1778 0.2794)
							(mid 0.249642 0.249642)
							(end 0.2794 0.1778)
						)
						(arc
							(start 0.2794 -0.1778)
							(mid 0.249642 -0.249642)
							(end 0.1778 -0.2794)
						)
					)
					(width 0)
					(fill yes)
				)
			)
		)
	)
)
